(kicad_pcb
	(version 20260206)
	(generator "pcbnew")
	(generator_version "10.0")
	(general
		(thickness 1.6)
		(legacy_teardrops no)
	)
	(paper "A4")
	(title_block
		(title "04192023_DAF0TMB3IC0_F0TG_MB_C_brd_V02_OCP.brd")
		(comment 1 "Grand Teton / footprints 2611-2617 of 8354")
	)
	(layers
		(0 "F.Cu" signal "TOP")
		(4 "In1.Cu" signal "GND")
		(6 "In2.Cu" signal "IN1")
		(8 "In3.Cu" signal "GND1")
		(10 "In4.Cu" signal "IN2")
		(12 "In5.Cu" signal "GND2")
		(14 "In6.Cu" signal "IN3")
		(16 "In7.Cu" signal "GND3")
		(18 "In8.Cu" signal "VCC")
		(20 "In9.Cu" signal "VCC1")
		(22 "In10.Cu" signal "GND4")
		(24 "In11.Cu" signal "IN4")
		(26 "In12.Cu" signal "GND5")
		(28 "In13.Cu" signal "IN5")
		(30 "In14.Cu" signal "GND6")
		(32 "In15.Cu" signal "IN6")
		(34 "In16.Cu" signal "GND7")
		(2 "B.Cu" signal "BOTTOM")
		(9 "F.Adhes" user "F.Adhesive")
		(11 "B.Adhes" user "B.Adhesive")
		(13 "F.Paste" user "Package Geometry/Pastemask Top")
		(15 "B.Paste" user "Package Geometry/Pastemask Bottom")
		(5 "F.SilkS" user "Ref Des/Silkscreen Top")
		(7 "B.SilkS" user "Ref Des/Silkscreen Bottom")
		(1 "F.Mask" user "Board Geometry/Soldermask Top")
		(3 "B.Mask" user "Board Geometry/Soldermask Bottom")
		(17 "Dwgs.User" user "User.Drawings")
		(19 "Cmts.User" user "User.Comments")
		(21 "Eco1.User" user "User.Eco1")
		(23 "Eco2.User" user "User.Eco2")
		(25 "Edge.Cuts" user "Board Geometry/Outline")
		(27 "Margin" user)
		(31 "F.CrtYd" user "Package Geometry/Place Bound Top")
		(29 "B.CrtYd" user "Package Geometry/Place Bound Bottom")
		(35 "F.Fab" user "Ref Des/Assembly Top")
		(33 "B.Fab" user "Ref Des/Assembly Bottom")
	)
	(footprint ""
		(layer "F.Cu")
		(at 194.914774 -424.622214 90)
		(property "Reference" "C8011"
			(at 0 0 90)
			(layer "F.SilkS")
			(hide yes)
			(effects
				(font
					(size 1.27 1.27)
				)
			)
		)
		(property "Value" ""
			(at 0 0 90)
			(layer "F.Fab")
			(effects
				(font
					(size 1.27 1.27)
				)
			)
		)
		(duplicate_pad_numbers_are_jumpers no)
		(fp_line
			(start 0.7874 -0.4064)
			(end 0.7874 0.4064)
			(stroke
				(width 0.1524)
				(type default)
			)
			(layer "F.SilkS")
		)
		(fp_line
			(start -0.7874 -0.4064)
			(end 0.7874 -0.4064)
			(stroke
				(width 0.1524)
				(type default)
			)
			(layer "F.SilkS")
		)
		(fp_line
			(start 0.7874 0.4064)
			(end -0.7874 0.4064)
			(stroke
				(width 0.1524)
				(type default)
			)
			(layer "F.SilkS")
		)
		(fp_line
			(start -0.7874 0.4064)
			(end -0.7874 -0.4064)
			(stroke
				(width 0.1524)
				(type default)
			)
			(layer "F.SilkS")
		)
		(fp_line
			(start -0.12065 -0.305054)
			(end -0.12065 -0.2794)
			(stroke
				(width 0.1)
				(type default)
			)
			(layer "F.Fab")
		)
		(fp_line
			(start -0.67945 -0.305054)
			(end -0.12065 -0.305054)
			(stroke
				(width 0.1)
				(type default)
			)
			(layer "F.Fab")
		)
		(fp_line
			(start 0.67945 -0.3048)
			(end 0.67945 0.3048)
			(stroke
				(width 0.1)
				(type default)
			)
			(layer "F.Fab")
		)
		(fp_line
			(start 0.12065 -0.3048)
			(end 0.67945 -0.3048)
			(stroke
				(width 0.1)
				(type default)
			)
			(layer "F.Fab")
		)
		(fp_line
			(start 0.12065 -0.2794)
			(end 0.12065 -0.3048)
			(stroke
				(width 0.1)
				(type default)
			)
			(layer "F.Fab")
		)
		(fp_line
			(start -0.12065 -0.2794)
			(end 0.12065 -0.2794)
			(stroke
				(width 0.1)
				(type default)
			)
			(layer "F.Fab")
		)
		(fp_line
			(start 0.120396 0.2794)
			(end -0.12065 0.2794)
			(stroke
				(width 0.1)
				(type default)
			)
			(layer "F.Fab")
		)
		(fp_line
			(start -0.12065 0.2794)
			(end -0.12065 0.3048)
			(stroke
				(width 0.1)
				(type default)
			)
			(layer "F.Fab")
		)
		(fp_line
			(start 0.67945 0.3048)
			(end 0.120396 0.3048)
			(stroke
				(width 0.1)
				(type default)
			)
			(layer "F.Fab")
		)
		(fp_line
			(start 0.120396 0.3048)
			(end 0.120396 0.2794)
			(stroke
				(width 0.1)
				(type default)
			)
			(layer "F.Fab")
		)
		(fp_line
			(start -0.12065 0.3048)
			(end -0.67945 0.3048)
			(stroke
				(width 0.1)
				(type default)
			)
			(layer "F.Fab")
		)
		(fp_line
			(start -0.67945 0.3048)
			(end -0.67945 -0.305054)
			(stroke
				(width 0.1)
				(type default)
			)
			(layer "F.Fab")
		)
		(pad "1" smd circle
			(at -0.40005 0 90)
			(size 0 0)
			(layers "F.Cu" "F.Mask" "F.Paste")
			(net "FM_AC_PWR_BTN_PDB_N")
		)
		(pad "2" smd circle
			(at 0.40005 0 90)
			(size 0 0)
			(layers "F.Cu" "F.Mask" "F.Paste")
			(net "GND")
		)
	)
	(footprint ""
		(layer "F.Cu")
		(at 276.520402 -76.110084 180)
		(property "Reference" ""
			(at 0 0 180)
			(layer "F.SilkS")
			(hide yes)
			(effects
				(font
					(size 1.27 1.27)
				)
			)
		)
		(property "Value" ""
			(at 0 0 180)
			(layer "F.Fab")
			(effects
				(font
					(size 1.27 1.27)
				)
			)
		)
		(duplicate_pad_numbers_are_jumpers no)
		(pad "1" smd circle
			(at 0 0 180)
			(size 0.9906 0.9906)
			(layers "F.Cu" "F.Mask" "F.Paste")
			(net "Net_44")
		)
		(zone
			(layer "F.Cu")
			(hatch none 0.5)
			(connect_pads
				(clearance 0)
			)
			(min_thickness 0.25)
			(keepout
				(tracks not_allowed)
				(vias allowed)
				(pads allowed)
				(copperpour not_allowed)
				(footprints allowed)
			)
			(placement
				(enabled no)
				(sheetname "")
			)
			(fill
				(thermal_gap 0.5)
				(thermal_bridge_width 0.5)
				(island_removal_mode 0)
			)
			(polygon
				(pts
					(arc
						(start 278.146002 -76.110084)
						(mid 274.894802 -76.110084)
						(end 278.146002 -76.110084)
					)
				)
			)
		)
	)
	(footprint ""
		(layer "F.Cu")
		(at 180.225954 -356.152958 90)
		(property "Reference" "PC503_1"
			(at 0 0 90)
			(layer "F.SilkS")
			(hide yes)
			(effects
				(font
					(size 1.27 1.27)
				)
			)
		)
		(property "Value" ""
			(at 0 0 90)
			(layer "F.Fab")
			(effects
				(font
					(size 1.27 1.27)
				)
			)
		)
		(duplicate_pad_numbers_are_jumpers no)
		(fp_line
			(start 0.7874 -0.4064)
			(end 0.7874 0.4064)
			(stroke
				(width 0.1524)
				(type default)
			)
			(layer "F.SilkS")
		)
		(fp_line
			(start -0.7874 -0.4064)
			(end 0.7874 -0.4064)
			(stroke
				(width 0.1524)
				(type default)
			)
			(layer "F.SilkS")
		)
		(fp_line
			(start 0.7874 0.4064)
			(end -0.7874 0.4064)
			(stroke
				(width 0.1524)
				(type default)
			)
			(layer "F.SilkS")
		)
		(fp_line
			(start -0.7874 0.4064)
			(end -0.7874 -0.4064)
			(stroke
				(width 0.1524)
				(type default)
			)
			(layer "F.SilkS")
		)
		(fp_line
			(start -0.12065 -0.305054)
			(end -0.12065 -0.2794)
			(stroke
				(width 0.1)
				(type default)
			)
			(layer "F.Fab")
		)
		(fp_line
			(start -0.67945 -0.305054)
			(end -0.12065 -0.305054)
			(stroke
				(width 0.1)
				(type default)
			)
			(layer "F.Fab")
		)
		(fp_line
			(start 0.67945 -0.3048)
			(end 0.67945 0.3048)
			(stroke
				(width 0.1)
				(type default)
			)
			(layer "F.Fab")
		)
		(fp_line
			(start 0.12065 -0.3048)
			(end 0.67945 -0.3048)
			(stroke
				(width 0.1)
				(type default)
			)
			(layer "F.Fab")
		)
		(fp_line
			(start 0.12065 -0.2794)
			(end 0.12065 -0.3048)
			(stroke
				(width 0.1)
				(type default)
			)
			(layer "F.Fab")
		)
		(fp_line
			(start -0.12065 -0.2794)
			(end 0.12065 -0.2794)
			(stroke
				(width 0.1)
				(type default)
			)
			(layer "F.Fab")
		)
		(fp_line
			(start 0.120396 0.2794)
			(end -0.12065 0.2794)
			(stroke
				(width 0.1)
				(type default)
			)
			(layer "F.Fab")
		)
		(fp_line
			(start -0.12065 0.2794)
			(end -0.12065 0.3048)
			(stroke
				(width 0.1)
				(type default)
			)
			(layer "F.Fab")
		)
		(fp_line
			(start 0.67945 0.3048)
			(end 0.120396 0.3048)
			(stroke
				(width 0.1)
				(type default)
			)
			(layer "F.Fab")
		)
		(fp_line
			(start 0.120396 0.3048)
			(end 0.120396 0.2794)
			(stroke
				(width 0.1)
				(type default)
			)
			(layer "F.Fab")
		)
		(fp_line
			(start -0.12065 0.3048)
			(end -0.67945 0.3048)
			(stroke
				(width 0.1)
				(type default)
			)
			(layer "F.Fab")
		)
		(fp_line
			(start -0.67945 0.3048)
			(end -0.67945 -0.305054)
			(stroke
				(width 0.1)
				(type default)
			)
			(layer "F.Fab")
		)
		(pad "1" smd circle
			(at -0.40005 0 90)
			(size 0 0)
			(layers "F.Cu" "F.Mask" "F.Paste")
			(net "PVDD11_S3_P1_VCCS")
		)
		(pad "2" smd circle
			(at 0.40005 0 90)
			(size 0 0)
			(layers "F.Cu" "F.Mask" "F.Paste")
			(net "GND")
		)
	)
	(footprint ""
		(layer "F.Cu")
		(at 384.390392 -65.541652 -90)
		(property "Reference" "C551"
			(at 0 0 270)
			(layer "F.SilkS")
			(hide yes)
			(effects
				(font
					(size 1.27 1.27)
				)
			)
		)
		(property "Value" ""
			(at 0 0 270)
			(layer "F.Fab")
			(effects
				(font
					(size 1.27 1.27)
				)
			)
		)
		(duplicate_pad_numbers_are_jumpers no)
		(fp_line
			(start -0.7874 0.4064)
			(end -0.7874 -0.4064)
			(stroke
				(width 0.1524)
				(type default)
			)
			(layer "F.SilkS")
		)
		(fp_line
			(start 0.7874 0.4064)
			(end -0.7874 0.4064)
			(stroke
				(width 0.1524)
				(type default)
			)
			(layer "F.SilkS")
		)
		(fp_line
			(start -0.7874 -0.4064)
			(end 0.7874 -0.4064)
			(stroke
				(width 0.1524)
				(type default)
			)
			(layer "F.SilkS")
		)
		(fp_line
			(start 0.7874 -0.4064)
			(end 0.7874 0.4064)
			(stroke
				(width 0.1524)
				(type default)
			)
			(layer "F.SilkS")
		)
		(fp_line
			(start -0.67945 0.3048)
			(end -0.67945 -0.305054)
			(stroke
				(width 0.1)
				(type default)
			)
			(layer "F.Fab")
		)
		(fp_line
			(start -0.12065 0.3048)
			(end -0.67945 0.3048)
			(stroke
				(width 0.1)
				(type default)
			)
			(layer "F.Fab")
		)
		(fp_line
			(start 0.120396 0.3048)
			(end 0.120396 0.2794)
			(stroke
				(width 0.1)
				(type default)
			)
			(layer "F.Fab")
		)
		(fp_line
			(start 0.67945 0.3048)
			(end 0.120396 0.3048)
			(stroke
				(width 0.1)
				(type default)
			)
			(layer "F.Fab")
		)
		(fp_line
			(start -0.12065 0.2794)
			(end -0.12065 0.3048)
			(stroke
				(width 0.1)
				(type default)
			)
			(layer "F.Fab")
		)
		(fp_line
			(start 0.120396 0.2794)
			(end -0.12065 0.2794)
			(stroke
				(width 0.1)
				(type default)
			)
			(layer "F.Fab")
		)
		(fp_line
			(start -0.12065 -0.2794)
			(end 0.12065 -0.2794)
			(stroke
				(width 0.1)
				(type default)
			)
			(layer "F.Fab")
		)
		(fp_line
			(start 0.12065 -0.2794)
			(end 0.12065 -0.3048)
			(stroke
				(width 0.1)
				(type default)
			)
			(layer "F.Fab")
		)
		(fp_line
			(start 0.12065 -0.3048)
			(end 0.67945 -0.3048)
			(stroke
				(width 0.1)
				(type default)
			)
			(layer "F.Fab")
		)
		(fp_line
			(start 0.67945 -0.3048)
			(end 0.67945 0.3048)
			(stroke
				(width 0.1)
				(type default)
			)
			(layer "F.Fab")
		)
		(fp_line
			(start -0.67945 -0.305054)
			(end -0.12065 -0.305054)
			(stroke
				(width 0.1)
				(type default)
			)
			(layer "F.Fab")
		)
		(fp_line
			(start -0.12065 -0.305054)
			(end -0.12065 -0.2794)
			(stroke
				(width 0.1)
				(type default)
			)
			(layer "F.Fab")
		)
		(pad "1" smd circle
			(at -0.40005 0 270)
			(size 0 0)
			(layers "F.Cu" "F.Mask" "F.Paste")
			(net "CPU0_HDT_CONN_TESTEN")
		)
		(pad "2" smd circle
			(at 0.40005 0 270)
			(size 0 0)
			(layers "F.Cu" "F.Mask" "F.Paste")
			(net "GND")
		)
	)
	(footprint ""
		(layer "F.Cu")
		(at 168.355518 -125.762004)
		(property "Reference" "R6139"
			(at 0 0 0)
			(layer "F.SilkS")
			(hide yes)
			(effects
				(font
					(size 1.27 1.27)
				)
			)
		)
		(property "Value" ""
			(at 0 0 0)
			(layer "F.Fab")
			(effects
				(font
					(size 1.27 1.27)
				)
			)
		)
		(duplicate_pad_numbers_are_jumpers no)
		(fp_line
			(start -0.7874 -0.4064)
			(end 0.7874 -0.4064)
			(stroke
				(width 0.1524)
				(type default)
			)
			(layer "F.SilkS")
		)
		(fp_line
			(start -0.7874 0.4064)
			(end -0.7874 -0.4064)
			(stroke
				(width 0.1524)
				(type default)
			)
			(layer "F.SilkS")
		)
		(fp_line
			(start 0.7874 -0.4064)
			(end 0.7874 0.4064)
			(stroke
				(width 0.1524)
				(type default)
			)
			(layer "F.SilkS")
		)
		(fp_line
			(start 0.7874 0.4064)
			(end -0.7874 0.4064)
			(stroke
				(width 0.1524)
				(type default)
			)
			(layer "F.SilkS")
		)
		(fp_line
			(start -0.67945 -0.305054)
			(end -0.12065 -0.305054)
			(stroke
				(width 0.1)
				(type default)
			)
			(layer "F.Fab")
		)
		(fp_line
			(start -0.67945 0.3048)
			(end -0.67945 -0.305054)
			(stroke
				(width 0.1)
				(type default)
			)
			(layer "F.Fab")
		)
		(fp_line
			(start -0.12065 -0.305054)
			(end -0.12065 -0.2794)
			(stroke
				(width 0.1)
				(type default)
			)
			(layer "F.Fab")
		)
		(fp_line
			(start -0.12065 -0.2794)
			(end 0.12065 -0.2794)
			(stroke
				(width 0.1)
				(type default)
			)
			(layer "F.Fab")
		)
		(fp_line
			(start -0.12065 0.2794)
			(end -0.12065 0.3048)
			(stroke
				(width 0.1)
				(type default)
			)
			(layer "F.Fab")
		)
		(fp_line
			(start -0.12065 0.3048)
			(end -0.67945 0.3048)
			(stroke
				(width 0.1)
				(type default)
			)
			(layer "F.Fab")
		)
		(fp_line
			(start 0.120396 0.2794)
			(end -0.12065 0.2794)
			(stroke
				(width 0.1)
				(type default)
			)
			(layer "F.Fab")
		)
		(fp_line
			(start 0.120396 0.3048)
			(end 0.120396 0.2794)
			(stroke
				(width 0.1)
				(type default)
			)
			(layer "F.Fab")
		)
		(fp_line
			(start 0.12065 -0.3048)
			(end 0.67945 -0.3048)
			(stroke
				(width 0.1)
				(type default)
			)
			(layer "F.Fab")
		)
		(fp_line
			(start 0.12065 -0.2794)
			(end 0.12065 -0.3048)
			(stroke
				(width 0.1)
				(type default)
			)
			(layer "F.Fab")
		)
		(fp_line
			(start 0.67945 -0.3048)
			(end 0.67945 0.3048)
			(stroke
				(width 0.1)
				(type default)
			)
			(layer "F.Fab")
		)
		(fp_line
			(start 0.67945 0.3048)
			(end 0.120396 0.3048)
			(stroke
				(width 0.1)
				(type default)
			)
			(layer "F.Fab")
		)
		(pad "1" smd circle
			(at -0.40005 0)
			(size 0 0)
			(layers "F.Cu" "F.Mask" "F.Paste")
			(net "P3V3_AUX")
		)
		(pad "2" smd circle
			(at 0.40005 0)
			(size 0 0)
			(layers "F.Cu" "F.Mask" "F.Paste")
			(net "FM_BOARD_BMC_SKU_ID1")
		)
	)
	(footprint ""
		(layer "F.Cu")
		(at 63.660528 -351.372932 -90)
		(property "Reference" "PC413"
			(at 0 0 270)
			(layer "F.SilkS")
			(hide yes)
			(effects
				(font
					(size 1.27 1.27)
				)
			)
		)
		(property "Value" ""
			(at 0 0 270)
			(layer "F.Fab")
			(effects
				(font
					(size 1.27 1.27)
				)
			)
		)
		(duplicate_pad_numbers_are_jumpers no)
		(fp_line
			(start -0.7874 0.4064)
			(end -0.7874 -0.4064)
			(stroke
				(width 0.1524)
				(type default)
			)
			(layer "F.SilkS")
		)
		(fp_line
			(start 0.7874 0.4064)
			(end -0.7874 0.4064)
			(stroke
				(width 0.1524)
				(type default)
			)
			(layer "F.SilkS")
		)
		(fp_line
			(start -0.7874 -0.4064)
			(end 0.7874 -0.4064)
			(stroke
				(width 0.1524)
				(type default)
			)
			(layer "F.SilkS")
		)
		(fp_line
			(start 0.7874 -0.4064)
			(end 0.7874 0.4064)
			(stroke
				(width 0.1524)
				(type default)
			)
			(layer "F.SilkS")
		)
		(fp_line
			(start -0.67945 0.3048)
			(end -0.67945 -0.305054)
			(stroke
				(width 0.1)
				(type default)
			)
			(layer "F.Fab")
		)
		(fp_line
			(start -0.12065 0.3048)
			(end -0.67945 0.3048)
			(stroke
				(width 0.1)
				(type default)
			)
			(layer "F.Fab")
		)
		(fp_line
			(start 0.120396 0.3048)
			(end 0.120396 0.2794)
			(stroke
				(width 0.1)
				(type default)
			)
			(layer "F.Fab")
		)
		(fp_line
			(start 0.67945 0.3048)
			(end 0.120396 0.3048)
			(stroke
				(width 0.1)
				(type default)
			)
			(layer "F.Fab")
		)
		(fp_line
			(start -0.12065 0.2794)
			(end -0.12065 0.3048)
			(stroke
				(width 0.1)
				(type default)
			)
			(layer "F.Fab")
		)
		(fp_line
			(start 0.120396 0.2794)
			(end -0.12065 0.2794)
			(stroke
				(width 0.1)
				(type default)
			)
			(layer "F.Fab")
		)
		(fp_line
			(start -0.12065 -0.2794)
			(end 0.12065 -0.2794)
			(stroke
				(width 0.1)
				(type default)
			)
			(layer "F.Fab")
		)
		(fp_line
			(start 0.12065 -0.2794)
			(end 0.12065 -0.3048)
			(stroke
				(width 0.1)
				(type default)
			)
			(layer "F.Fab")
		)
		(fp_line
			(start 0.12065 -0.3048)
			(end 0.67945 -0.3048)
			(stroke
				(width 0.1)
				(type default)
			)
			(layer "F.Fab")
		)
		(fp_line
			(start 0.67945 -0.3048)
			(end 0.67945 0.3048)
			(stroke
				(width 0.1)
				(type default)
			)
			(layer "F.Fab")
		)
		(fp_line
			(start -0.67945 -0.305054)
			(end -0.12065 -0.305054)
			(stroke
				(width 0.1)
				(type default)
			)
			(layer "F.Fab")
		)
		(fp_line
			(start -0.12065 -0.305054)
			(end -0.12065 -0.2794)
			(stroke
				(width 0.1)
				(type default)
			)
			(layer "F.Fab")
		)
		(pad "1" smd circle
			(at -0.40005 0 270)
			(size 0 0)
			(layers "F.Cu" "F.Mask" "F.Paste")
			(net "SW_PVDDCR_CPU1_P1_BOOT4_R")
		)
		(pad "2" smd circle
			(at 0.40005 0 270)
			(size 0 0)
			(layers "F.Cu" "F.Mask" "F.Paste")
			(net "SW_PVDDCR_CPU1_P1_BOOTR4")
		)
	)
	(footprint ""
		(layer "F.Cu")
		(at 239.152684 -52.92725)
		(property "Reference" "C1996"
			(at 0 0 0)
			(layer "F.SilkS")
			(hide yes)
			(effects
				(font
					(size 1.27 1.27)
				)
			)
		)
		(property "Value" ""
			(at 0 0 0)
			(layer "F.Fab")
			(effects
				(font
					(size 1.27 1.27)
				)
			)
		)
		(duplicate_pad_numbers_are_jumpers no)
		(fp_line
			(start -0.299974 -0.150114)
			(end 0.299974 -0.150114)
			(stroke
				(width 0.1)
				(type default)
			)
			(layer "F.Fab")
		)
		(fp_line
			(start -0.299974 0.150114)
			(end -0.299974 -0.150114)
			(stroke
				(width 0.1)
				(type default)
			)
			(layer "F.Fab")
		)
		(fp_line
			(start 0.299974 -0.150114)
			(end 0.299974 0.150114)
			(stroke
				(width 0.1)
				(type default)
			)
			(layer "F.Fab")
		)
		(fp_line
			(start 0.299974 0.150114)
			(end -0.299974 0.150114)
			(stroke
				(width 0.1)
				(type default)
			)
			(layer "F.Fab")
		)
		(pad "1" smd rect
			(at -0.2667 0)
			(size 0.3048 0.381)
			(layers "F.Cu" "F.Mask" "F.Paste")
			(net "P3E_CPU0_P4_TX_C_DN<0>")
		)
		(pad "2" smd rect
			(at 0.2667 0)
			(size 0.3048 0.381)
			(layers "F.Cu" "F.Mask" "F.Paste")
			(net "P3E_CPU0_P4_TX_DN<0>")
		)
	)
)
